(kicad_pcb
	(version 20260206)
	(generator "pcbnew")
	(generator_version "10.0")
	(general
		(thickness 1.6)
		(legacy_teardrops no)
	)
	(paper "A4")
	(title_block
		(title "dpb — 14545-sa.0730WZS0815.brd")
		(comment 1 "Honey Badger (Wiwynn) / footprints 772-778 of 1066")
	)
	(layers
		(0 "F.Cu" signal "TOP")
		(4 "In1.Cu" signal "L2GND")
		(6 "In2.Cu" signal "L3")
		(8 "In3.Cu" signal "L4VCC")
		(10 "In4.Cu" signal "L5VCC")
		(12 "In5.Cu" signal "L6")
		(14 "In6.Cu" signal "L7GND")
		(2 "B.Cu" signal "BOTTOM")
		(9 "F.Adhes" user "F.Adhesive")
		(11 "B.Adhes" user "B.Adhesive")
		(13 "F.Paste" user "Package Geometry/Pastemask Top")
		(15 "B.Paste" user "Package Geometry/Pastemask Bottom")
		(5 "F.SilkS" user "Ref Des/Silkscreen Top")
		(7 "B.SilkS" user "Ref Des/Silkscreen Bottom")
		(1 "F.Mask" user "Board Geometry/Soldermask Top")
		(3 "B.Mask" user "Board Geometry/Soldermask Bottom")
		(17 "Dwgs.User" user "User.Drawings")
		(19 "Cmts.User" user "User.Comments")
		(21 "Eco1.User" user "User.Eco1")
		(23 "Eco2.User" user "User.Eco2")
		(25 "Edge.Cuts" user "Board Geometry/Outline")
		(27 "Margin" user)
		(31 "F.CrtYd" user "Package Geometry/Place Bound Top")
		(29 "B.CrtYd" user "Package Geometry/Place Bound Bottom")
		(35 "F.Fab" user "Ref Des/Assembly Top")
		(33 "B.Fab" user "Ref Des/Assembly Bottom")
	)
	(footprint ""
		(layer "F.Cu")
		(at 229.488746 -33.0327 180)
		(property "Reference" "PR6"
			(at 0 0 180)
			(layer "F.SilkS")
			(hide yes)
			(effects
				(font
					(size 1.27 1.27)
				)
			)
		)
		(property "Value" "10R2F-L-GP"
			(at 0.064008 -3.993896 180)
			(unlocked yes)
			(layer "F.Fab")
			(hide yes)
			(effects
				(font
					(size 1.016 1.016)
					(thickness 0.1524)
				)
			)
		)
		(property "Device Type" "R402H14"
			(at 0.064008 -5.517896 180)
			(unlocked yes)
			(layer "F.Fab")
			(hide yes)
			(effects
				(font
					(size 1.016 1.016)
					(thickness 0.1524)
				)
			)
		)
		(duplicate_pad_numbers_are_jumpers no)
		(fp_line
			(start 0.508 -0.9398)
			(end -0.508 -0.9398)
			(stroke
				(width 0.1524)
				(type default)
			)
			(layer "F.SilkS")
		)
		(fp_line
			(start -0.508 -0.9398)
			(end -0.508 0.9398)
			(stroke
				(width 0.1524)
				(type default)
			)
			(layer "F.SilkS")
		)
		(fp_rect
			(start -0.508 0.9398)
			(end 0.508 -0.9398)
			(stroke
				(width 0)
				(type default)
			)
			(fill no)
			(layer "F.CrtYd")
		)
		(fp_rect
			(start -0.508 0.9398)
			(end 0.508 -0.9398)
			(stroke
				(width 0)
				(type default)
			)
			(fill no)
			(layer "F.Fab")
		)
		(pad "1" smd custom
			(at 0 -0.4445 180)
			(size 0.1397 0.1397)
			(layers "F.Cu" "F.Mask" "F.Paste")
			(net "P5VA")
			(options
				(clearance outline)
				(anchor circle)
			)
			(primitives
				(gr_poly
					(pts
						(arc
							(start -0.1778 -0.2794)
							(mid -0.249642 -0.249642)
							(end -0.2794 -0.1778)
						)
						(arc
							(start -0.2794 0.1778)
							(mid -0.249642 0.249642)
							(end -0.1778 0.2794)
						)
						(arc
							(start 0.1778 0.2794)
							(mid 0.249642 0.249642)
							(end 0.2794 0.1778)
						)
						(arc
							(start 0.2794 -0.1778)
							(mid 0.249642 -0.249642)
							(end 0.1778 -0.2794)
						)
					)
					(width 0)
					(fill yes)
				)
			)
		)
		(pad "2" smd custom
			(at 0 0.4445 180)
			(size 0.1397 0.1397)
			(layers "F.Cu" "F.Mask" "F.Paste")
			(net "P5VA_VFB_NET")
			(options
				(clearance outline)
				(anchor circle)
			)
			(primitives
				(gr_poly
					(pts
						(arc
							(start -0.1778 -0.2794)
							(mid -0.249642 -0.249642)
							(end -0.2794 -0.1778)
						)
						(arc
							(start -0.2794 0.1778)
							(mid -0.249642 0.249642)
							(end -0.1778 0.2794)
						)
						(arc
							(start 0.1778 0.2794)
							(mid 0.249642 0.249642)
							(end 0.2794 0.1778)
						)
						(arc
							(start 0.2794 -0.1778)
							(mid 0.249642 -0.249642)
							(end 0.1778 -0.2794)
						)
					)
					(width 0)
					(fill yes)
				)
			)
		)
	)
	(footprint ""
		(layer "F.Cu")
		(at 77.342746 -11.077702 90)
		(property "Reference" "R304"
			(at 0 0 90)
			(layer "F.SilkS")
			(hide yes)
			(effects
				(font
					(size 1.27 1.27)
				)
			)
		)
		(property "Value" "2R2010J-1-GP"
			(at 0.254 -8.0772 90)
			(unlocked yes)
			(layer "F.Fab")
			(hide yes)
			(effects
				(font
					(size 1.016 1.016)
					(thickness 0.1524)
				)
			)
		)
		(property "Device Type" "R2010H28"
			(at 0.254 -9.6774 90)
			(unlocked yes)
			(layer "F.Fab")
			(hide yes)
			(effects
				(font
					(size 1.016 1.016)
					(thickness 0.1524)
				)
			)
		)
		(duplicate_pad_numbers_are_jumpers no)
		(fp_line
			(start 1.651 -3.302)
			(end -1.651 -3.302)
			(stroke
				(width 0.1524)
				(type default)
			)
			(layer "F.SilkS")
		)
		(fp_line
			(start -1.651 -3.302)
			(end -1.651 3.302)
			(stroke
				(width 0.1524)
				(type default)
			)
			(layer "F.SilkS")
		)
		(fp_line
			(start 1.651 3.302)
			(end 1.651 -3.302)
			(stroke
				(width 0.1524)
				(type default)
			)
			(layer "F.SilkS")
		)
		(fp_line
			(start -1.651 3.302)
			(end 1.651 3.302)
			(stroke
				(width 0.1524)
				(type default)
			)
			(layer "F.SilkS")
		)
		(fp_rect
			(start -1.7272 -3.3782)
			(end 1.7272 3.3782)
			(stroke
				(width 0)
				(type default)
			)
			(fill no)
			(layer "F.CrtYd")
		)
		(fp_poly
			(pts
				(xy 1.7272 3.3782) (xy 1.7272 -3.3782) (xy -1.7272 -3.3782) (xy -1.7272 3.3782)
			)
			(stroke
				(width 0)
				(type default)
			)
			(fill no)
			(layer "F.Fab")
		)
		(pad "1" smd rect
			(at 0 -2.3495 90)
			(size 2.794 1.143)
			(layers "F.Cu" "F.Mask" "F.Paste")
			(net "12V_PRE_14")
		)
		(pad "2" smd rect
			(at 0 2.3495 90)
			(size 2.794 1.143)
			(layers "F.Cu" "F.Mask" "F.Paste")
			(net "P12V_HDD14")
		)
	)
	(footprint ""
		(layer "F.Cu")
		(at 77.978 -94.488)
		(property "Reference" "R572"
			(at 0 0 0)
			(layer "F.SilkS")
			(hide yes)
			(effects
				(font
					(size 1.27 1.27)
				)
			)
		)
		(property "Value" "300KR2F-GP"
			(at 0.064008 -3.993896 0)
			(unlocked yes)
			(layer "F.Fab")
			(hide yes)
			(effects
				(font
					(size 1.016 1.016)
					(thickness 0.1524)
				)
			)
		)
		(property "Device Type" "R402H16"
			(at 0.064008 -5.517896 0)
			(unlocked yes)
			(layer "F.Fab")
			(hide yes)
			(effects
				(font
					(size 1.016 1.016)
					(thickness 0.1524)
				)
			)
		)
		(duplicate_pad_numbers_are_jumpers no)
		(fp_line
			(start -0.508 -0.9398)
			(end -0.508 0.9398)
			(stroke
				(width 0.1524)
				(type default)
			)
			(layer "F.SilkS")
		)
		(fp_line
			(start 0.508 -0.9398)
			(end -0.508 -0.9398)
			(stroke
				(width 0.1524)
				(type default)
			)
			(layer "F.SilkS")
		)
		(fp_rect
			(start -0.508 0.9398)
			(end 0.508 -0.9398)
			(stroke
				(width 0)
				(type default)
			)
			(fill no)
			(layer "F.CrtYd")
		)
		(fp_rect
			(start -0.508 0.9398)
			(end 0.508 -0.9398)
			(stroke
				(width 0)
				(type default)
			)
			(fill no)
			(layer "F.Fab")
		)
		(pad "1" smd custom
			(at 0 -0.4445)
			(size 0.1397 0.1397)
			(layers "F.Cu" "F.Mask" "F.Paste")
			(net "SW_HDD9_N")
			(options
				(clearance outline)
				(anchor circle)
			)
			(primitives
				(gr_poly
					(pts
						(arc
							(start -0.1778 -0.2794)
							(mid -0.249642 -0.249642)
							(end -0.2794 -0.1778)
						)
						(arc
							(start -0.2794 0.1778)
							(mid -0.249642 0.249642)
							(end -0.1778 0.2794)
						)
						(arc
							(start 0.1778 0.2794)
							(mid 0.249642 0.249642)
							(end 0.2794 0.1778)
						)
						(arc
							(start 0.2794 -0.1778)
							(mid 0.249642 -0.249642)
							(end 0.1778 -0.2794)
						)
					)
					(width 0)
					(fill yes)
				)
			)
		)
		(pad "2" smd custom
			(at 0 0.4445)
			(size 0.1397 0.1397)
			(layers "F.Cu" "F.Mask" "F.Paste")
			(net "P12V")
			(options
				(clearance outline)
				(anchor circle)
			)
			(primitives
				(gr_poly
					(pts
						(arc
							(start -0.1778 -0.2794)
							(mid -0.249642 -0.249642)
							(end -0.2794 -0.1778)
						)
						(arc
							(start -0.2794 0.1778)
							(mid -0.249642 0.249642)
							(end -0.1778 0.2794)
						)
						(arc
							(start 0.1778 0.2794)
							(mid 0.249642 0.249642)
							(end 0.2794 0.1778)
						)
						(arc
							(start 0.2794 -0.1778)
							(mid 0.249642 -0.249642)
							(end 0.1778 -0.2794)
						)
					)
					(width 0)
					(fill yes)
				)
			)
		)
	)
	(footprint ""
		(layer "F.Cu")
		(at 203.245974 -390.878822 -90)
		(property "Reference" "R426"
			(at 0 0 270)
			(layer "F.SilkS")
			(hide yes)
			(effects
				(font
					(size 1.27 1.27)
				)
			)
		)
		(property "Value" "4K7R2J-2-GP"
			(at 0.064008 -3.993896 270)
			(unlocked yes)
			(layer "F.Fab")
			(hide yes)
			(effects
				(font
					(size 1.016 1.016)
					(thickness 0.1524)
				)
			)
		)
		(property "Device Type" "R402H16"
			(at 0.064008 -5.517896 270)
			(unlocked yes)
			(layer "F.Fab")
			(hide yes)
			(effects
				(font
					(size 1.016 1.016)
					(thickness 0.1524)
				)
			)
		)
		(duplicate_pad_numbers_are_jumpers no)
		(fp_line
			(start -0.508 -0.9398)
			(end -0.508 0.9398)
			(stroke
				(width 0.1524)
				(type default)
			)
			(layer "F.SilkS")
		)
		(fp_line
			(start 0.508 -0.9398)
			(end -0.508 -0.9398)
			(stroke
				(width 0.1524)
				(type default)
			)
			(layer "F.SilkS")
		)
		(fp_rect
			(start -0.508 0.9398)
			(end 0.508 -0.9398)
			(stroke
				(width 0)
				(type default)
			)
			(fill no)
			(layer "F.CrtYd")
		)
		(fp_rect
			(start -0.508 0.9398)
			(end 0.508 -0.9398)
			(stroke
				(width 0)
				(type default)
			)
			(fill no)
			(layer "F.Fab")
		)
		(pad "1" smd custom
			(at 0 -0.4445 270)
			(size 0.1397 0.1397)
			(layers "F.Cu" "F.Mask" "F.Paste")
			(net "P3V3")
			(options
				(clearance outline)
				(anchor circle)
			)
			(primitives
				(gr_poly
					(pts
						(arc
							(start -0.1778 -0.2794)
							(mid -0.249642 -0.249642)
							(end -0.2794 -0.1778)
						)
						(arc
							(start -0.2794 0.1778)
							(mid -0.249642 0.249642)
							(end -0.1778 0.2794)
						)
						(arc
							(start 0.1778 0.2794)
							(mid 0.249642 0.249642)
							(end 0.2794 0.1778)
						)
						(arc
							(start 0.2794 -0.1778)
							(mid 0.249642 -0.249642)
							(end 0.1778 -0.2794)
						)
					)
					(width 0)
					(fill yes)
				)
			)
		)
		(pad "2" smd custom
			(at 0 0.4445 270)
			(size 0.1397 0.1397)
			(layers "F.Cu" "F.Mask" "F.Paste")
			(net "SAS2X28_B_HDD1_FLT")
			(options
				(clearance outline)
				(anchor circle)
			)
			(primitives
				(gr_poly
					(pts
						(arc
							(start -0.1778 -0.2794)
							(mid -0.249642 -0.249642)
							(end -0.2794 -0.1778)
						)
						(arc
							(start -0.2794 0.1778)
							(mid -0.249642 0.249642)
							(end -0.1778 0.2794)
						)
						(arc
							(start 0.1778 0.2794)
							(mid 0.249642 0.249642)
							(end 0.2794 0.1778)
						)
						(arc
							(start 0.2794 -0.1778)
							(mid 0.249642 -0.249642)
							(end 0.1778 -0.2794)
						)
					)
					(width 0)
					(fill yes)
				)
			)
		)
	)
	(footprint ""
		(layer "F.Cu")
		(at 93.090746 -7.3787 90)
		(property "Reference" "U44"
			(at 0 0 90)
			(layer "F.SilkS")
			(hide yes)
			(effects
				(font
					(size 1.27 1.27)
				)
			)
		)
		(property "Value" "P2003EVG-GP"
			(at 0 -11.1252 90)
			(unlocked yes)
			(layer "F.Fab")
			(hide yes)
			(effects
				(font
					(size 1.016 1.016)
					(thickness 0.1524)
				)
			)
		)
		(property "Device Type" "SOIC8H79"
			(at 0 -12.6492 90)
			(unlocked yes)
			(layer "F.Fab")
			(hide yes)
			(effects
				(font
					(size 1.016 1.016)
					(thickness 0.1524)
				)
			)
		)
		(duplicate_pad_numbers_are_jumpers no)
		(fp_line
			(start 2.1336 -1.4224)
			(end -2.7432 -1.4224)
			(stroke
				(width 0.1524)
				(type default)
			)
			(layer "F.SilkS")
		)
		(fp_line
			(start -2.7432 -1.4224)
			(end -2.7432 1.4224)
			(stroke
				(width 0.1524)
				(type default)
			)
			(layer "F.SilkS")
		)
		(fp_line
			(start -2.7432 -0.508)
			(end -2.2352 0)
			(stroke
				(width 0.1524)
				(type default)
			)
			(layer "F.SilkS")
		)
		(fp_line
			(start -2.2352 0)
			(end -2.7432 0.508)
			(stroke
				(width 0.1524)
				(type default)
			)
			(layer "F.SilkS")
		)
		(fp_line
			(start 2.1336 1.4224)
			(end 2.1336 -1.4224)
			(stroke
				(width 0.1524)
				(type default)
			)
			(layer "F.SilkS")
		)
		(fp_line
			(start -2.7432 1.4224)
			(end 2.1336 1.4224)
			(stroke
				(width 0.1524)
				(type default)
			)
			(layer "F.SilkS")
		)
		(fp_line
			(start -2.6162 3.429)
			(end -2.6162 1.4732)
			(stroke
				(width 0.4064)
				(type default)
			)
			(layer "F.SilkS")
		)
		(fp_poly
			(pts
				(xy 2.2098 -1.4224) (xy 2.2098 1.4224) (xy -2.2225 1.4224) (xy -2.2225 -1.4224)
			)
			(stroke
				(width 0)
				(type default)
			)
			(fill yes)
			(layer "F.SilkS")
		)
		(fp_rect
			(start -2.4511 2.9972)
			(end 2.4511 -2.9972)
			(stroke
				(width 0)
				(type default)
			)
			(fill no)
			(layer "F.CrtYd")
		)
		(fp_poly
			(pts
				(xy -2.8194 3.6322) (xy -2.8194 -3.6322) (xy 2.8194 -3.6322) (xy 2.8194 -2.2987) (xy 2.4511 -2.2987)
				(xy 2.4511 -2.9972) (xy -2.4511 -2.9972) (xy -2.4511 2.9972) (xy 2.4511 2.9972) (xy 2.4511 -2.286)
				(xy 2.8194 -2.286) (xy 2.8194 3.6322)
			)
			(stroke
				(width 0)
				(type default)
			)
			(fill no)
			(layer "F.CrtYd")
		)
		(fp_rect
			(start -2.8194 3.6322)
			(end 2.8194 -3.6322)
			(stroke
				(width 0)
				(type default)
			)
			(fill no)
			(layer "F.Fab")
		)
		(pad "1" smd rect
			(at -1.905 2.54 90)
			(size 0.635 1.651)
			(layers "F.Cu" "F.Mask" "F.Paste")
			(net "P12V")
		)
		(pad "2" smd rect
			(at -0.635 2.54 90)
			(size 0.635 1.651)
			(layers "F.Cu" "F.Mask" "F.Paste")
			(net "P12V")
		)
		(pad "3" smd rect
			(at 0.635 2.54 90)
			(size 0.635 1.651)
			(layers "F.Cu" "F.Mask" "F.Paste")
			(net "P12V")
		)
		(pad "4" smd rect
			(at 1.905 2.54 90)
			(size 0.635 1.651)
			(layers "F.Cu" "F.Mask" "F.Paste")
			(net "SW_HDD14_N")
		)
		(pad "5" smd rect
			(at 1.905 -2.54 90)
			(size 0.635 1.651)
			(layers "F.Cu" "F.Mask" "F.Paste")
			(net "P12V_HDD14")
		)
		(pad "6" smd rect
			(at 0.635 -2.54 90)
			(size 0.635 1.651)
			(layers "F.Cu" "F.Mask" "F.Paste")
			(net "P12V_HDD14")
		)
		(pad "7" smd rect
			(at -0.635 -2.54 90)
			(size 0.635 1.651)
			(layers "F.Cu" "F.Mask" "F.Paste")
			(net "P12V_HDD14")
		)
		(pad "8" smd rect
			(at -1.905 -2.54 90)
			(size 0.635 1.651)
			(layers "F.Cu" "F.Mask" "F.Paste")
			(net "P12V_HDD14")
		)
	)
	(footprint ""
		(layer "F.Cu")
		(at 58.5216 -71.882 90)
		(property "Reference" "R394"
			(at 0 0 90)
			(layer "F.SilkS")
			(hide yes)
			(effects
				(font
					(size 1.27 1.27)
				)
			)
		)
		(property "Value" "0R2J-2-GP"
			(at 0.064008 -3.993896 90)
			(unlocked yes)
			(layer "F.Fab")
			(hide yes)
			(effects
				(font
					(size 1.016 1.016)
					(thickness 0.1524)
				)
			)
		)
		(property "Device Type" "R402H16"
			(at 0.064008 -5.517896 90)
			(unlocked yes)
			(layer "F.Fab")
			(hide yes)
			(effects
				(font
					(size 1.016 1.016)
					(thickness 0.1524)
				)
			)
		)
		(duplicate_pad_numbers_are_jumpers no)
		(fp_line
			(start 0.508 -0.9398)
			(end -0.508 -0.9398)
			(stroke
				(width 0.1524)
				(type default)
			)
			(layer "F.SilkS")
		)
		(fp_line
			(start -0.508 -0.9398)
			(end -0.508 0.9398)
			(stroke
				(width 0.1524)
				(type default)
			)
			(layer "F.SilkS")
		)
		(fp_rect
			(start -0.508 0.9398)
			(end 0.508 -0.9398)
			(stroke
				(width 0)
				(type default)
			)
			(fill no)
			(layer "F.CrtYd")
		)
		(fp_rect
			(start -0.508 0.9398)
			(end 0.508 -0.9398)
			(stroke
				(width 0)
				(type default)
			)
			(fill no)
			(layer "F.Fab")
		)
		(pad "1" smd custom
			(at 0 -0.4445 90)
			(size 0.1397 0.1397)
			(layers "F.Cu" "F.Mask" "F.Paste")
			(net "HDD_PRSNT_NET9")
			(options
				(clearance outline)
				(anchor circle)
			)
			(primitives
				(gr_poly
					(pts
						(arc
							(start -0.1778 -0.2794)
							(mid -0.249642 -0.249642)
							(end -0.2794 -0.1778)
						)
						(arc
							(start -0.2794 0.1778)
							(mid -0.249642 0.249642)
							(end -0.1778 0.2794)
						)
						(arc
							(start 0.1778 0.2794)
							(mid 0.249642 0.249642)
							(end 0.2794 0.1778)
						)
						(arc
							(start 0.2794 -0.1778)
							(mid 0.249642 -0.249642)
							(end 0.1778 -0.2794)
						)
					)
					(width 0)
					(fill yes)
				)
			)
		)
		(pad "2" smd custom
			(at 0 0.4445 90)
			(size 0.1397 0.1397)
			(layers "F.Cu" "F.Mask" "F.Paste")
			(net "HDD9_LED_B")
			(options
				(clearance outline)
				(anchor circle)
			)
			(primitives
				(gr_poly
					(pts
						(arc
							(start -0.1778 -0.2794)
							(mid -0.249642 -0.249642)
							(end -0.2794 -0.1778)
						)
						(arc
							(start -0.2794 0.1778)
							(mid -0.249642 0.249642)
							(end -0.1778 0.2794)
						)
						(arc
							(start 0.1778 0.2794)
							(mid 0.249642 0.249642)
							(end 0.2794 0.1778)
						)
						(arc
							(start 0.2794 -0.1778)
							(mid 0.249642 -0.249642)
							(end 0.1778 -0.2794)
						)
					)
					(width 0)
					(fill yes)
				)
			)
		)
	)
	(footprint ""
		(layer "F.Cu")
		(at 5.079746 -493.7887 90)
		(property "Reference" "PR41"
			(at 0 0 90)
			(layer "F.SilkS")
			(hide yes)
			(effects
				(font
					(size 1.27 1.27)
				)
			)
		)
		(property "Value" "10KR2F-2-GP"
			(at 0.064008 -3.993896 90)
			(unlocked yes)
			(layer "F.Fab")
			(hide yes)
			(effects
				(font
					(size 1.016 1.016)
					(thickness 0.1524)
				)
			)
		)
		(property "Device Type" "R402H16"
			(at 0.064008 -5.517896 90)
			(unlocked yes)
			(layer "F.Fab")
			(hide yes)
			(effects
				(font
					(size 1.016 1.016)
					(thickness 0.1524)
				)
			)
		)
		(duplicate_pad_numbers_are_jumpers no)
		(fp_line
			(start 0.508 -0.9398)
			(end -0.508 -0.9398)
			(stroke
				(width 0.1524)
				(type default)
			)
			(layer "F.SilkS")
		)
		(fp_line
			(start -0.508 -0.9398)
			(end -0.508 0.9398)
			(stroke
				(width 0.1524)
				(type default)
			)
			(layer "F.SilkS")
		)
		(fp_rect
			(start -0.508 0.9398)
			(end 0.508 -0.9398)
			(stroke
				(width 0)
				(type default)
			)
			(fill no)
			(layer "F.CrtYd")
		)
		(fp_rect
			(start -0.508 0.9398)
			(end 0.508 -0.9398)
			(stroke
				(width 0)
				(type default)
			)
			(fill no)
			(layer "F.Fab")
		)
		(pad "1" smd custom
			(at 0 -0.4445 90)
			(size 0.1397 0.1397)
			(layers "F.Cu" "F.Mask" "F.Paste")
			(net "P5VC_12VIN")
			(options
				(clearance outline)
				(anchor circle)
			)
			(primitives
				(gr_poly
					(pts
						(arc
							(start -0.1778 -0.2794)
							(mid -0.249642 -0.249642)
							(end -0.2794 -0.1778)
						)
						(arc
							(start -0.2794 0.1778)
							(mid -0.249642 0.249642)
							(end -0.1778 0.2794)
						)
						(arc
							(start 0.1778 0.2794)
							(mid 0.249642 0.249642)
							(end 0.2794 0.1778)
						)
						(arc
							(start 0.2794 -0.1778)
							(mid 0.249642 -0.249642)
							(end 0.1778 -0.2794)
						)
					)
					(width 0)
					(fill yes)
				)
			)
		)
		(pad "2" smd custom
			(at 0 0.4445 90)
			(size 0.1397 0.1397)
			(layers "F.Cu" "F.Mask" "F.Paste")
			(net "P5VC_EN")
			(options
				(clearance outline)
				(anchor circle)
			)
			(primitives
				(gr_poly
					(pts
						(arc
							(start -0.1778 -0.2794)
							(mid -0.249642 -0.249642)
							(end -0.2794 -0.1778)
						)
						(arc
							(start -0.2794 0.1778)
							(mid -0.249642 0.249642)
							(end -0.1778 0.2794)
						)
						(arc
							(start 0.1778 0.2794)
							(mid 0.249642 0.249642)
							(end 0.2794 0.1778)
						)
						(arc
							(start 0.2794 -0.1778)
							(mid 0.249642 -0.249642)
							(end 0.1778 -0.2794)
						)
					)
					(width 0)
					(fill yes)
				)
			)
		)
	)
)
